FILE_TYPE = MULTI_PHYS_TABLE;

PART 'DUMMY_SYMBOL'

{========================================================================================}
:VALUE                      | PART_TYPE | MATERIAL | PART_NUMBER    = STANDARD | LIFECYCLE | PART_NUMBER | JEDEC_TYPE                 | DESCRIPTION                       | MANUFTR | MANUF_PN | RD_CMPLS_LVL | CMPLS_LVL | CLASS | DIP_SMD | FROM_PJ      | DATA | FP_ECN | EE_CHECK_LIST | PSL | PREFERENCE | CREATOR | CREATEDAY  | STATUS ;
{========================================================================================}
 'MECHANIC_SYMBOL'          | 'Mech'    | 'MECH'   | 'DUMMY10'(!)   = ''       | ''        | 'DUMMY10'   |'TP30_FOR_BOM'| 'MECHANIC_SYMBOL'                 | ''      | ''       | ''           | ''        | 'IO'  | ''      | ''           | ''   | ''     | ''            | ''  | ''         | ''      | '20141104' | ''    
 'MECHANIC_SYMBOL'          | 'Mech'    | 'EMPTY'  | 'DUMMY10'(!)   = ''       | ''        | 'DUMMY10'   |'TP30_FOR_BOM'| 'MECHANIC_SYMBOL'                 | ''      | ''       | ''           | ''        | 'IO'  | ''      | ''           | ''   | ''     | ''            | ''  | ''         | ''      | '20141104' | ''    
 'THERMAL_SYMBOL'           | 'Mech'    | 'MECH'   | 'DUMMY11'(!)   = ''       | ''        | 'DUMMY11'   |'TP30_FOR_BOM'| 'THERMAL_SYMBOL'                  | ''      | ''       | ''           | ''        | 'IO'  | ''      | ''           | ''   | ''     | ''            | ''  | ''         | ''      | '20141104' | ''    
 'THERMAL_SYMBOL'           | 'Mech'    | 'EMPTY'  | 'DUMMY11'(!)   = ''       | ''        | 'DUMMY11'   |'TP30_FOR_BOM'| 'THERMAL_SYMBOL'                  | ''      | ''       | ''           | ''        | 'IO'  | ''      | ''           | ''   | ''     | ''            | ''  | ''         | ''      | '20141104' | ''    
 'BATTERY_SYMBOL'           | 'Mech'    | 'MECH'   | 'DUMMY12'(!)   = ''       | ''        | 'DUMMY12'   |'TP30_FOR_BOM'| 'BATTERY_SYMBOL'                  | ''      | ''       | ''           | ''        | 'IO'  | ''      | ''           | ''   | ''     | ''            | ''  | ''         | ''      | '20141104' | ''    
 'BATTERY_SYMBOL'           | 'Mech'    | 'EMPTY'  | 'DUMMY12'(!)   = ''       | ''        | 'DUMMY12'   |'TP30_FOR_BOM'| 'BATTERY_SYMBOL'                  | ''      | ''       | ''           | ''        | 'IO'  | ''      | ''           | ''   | ''     | ''            | ''  | ''         | ''      | '20141104' | ''    
 'BMC_FLASH'                | 'Mech'    | 'MECH'   | 'DUMMY8'(!)    = ''       | ''        | 'DUMMY8'    |'TP30_FOR_BOM'| 'BMC_FLASH'                       | ''      | ''       | ''           | ''        | 'IO'  | ''      | ''           | ''   | ''     | ''            | ''  | ''         | ''      | '20141104' | ''    
 'BMC_FLASH'                | 'Mech'    | 'EMPTY'  | 'DUMMY8'(!)    = ''       | ''        | 'DUMMY8'    |'TP30_FOR_BOM'| 'BMC_FLASH'                       | ''      | ''       | ''           | ''        | 'IO'  | ''      | ''           | ''   | ''     | ''            | ''  | ''         | ''      | '20141104' | ''    
 'BIOS_FLASH'               | 'Mech'    | 'MECH'   | 'DUMMY9'(!)    = ''       | ''        | 'DUMMY9'    |'TP30_FOR_BOM'| 'BIOS_FLASH'                      | ''      | ''       | ''           | ''        | 'IO'  | ''      | ''           | ''   | ''     | ''            | ''  | ''         | ''      | '20141104' | ''    
 'BIOS_FLASH'               | 'Mech'    | 'EMPTY'  | 'DUMMY9'(!)    = ''       | ''        | 'DUMMY9'    |'TP30_FOR_BOM'| 'BIOS_FLASH'                      | ''      | ''       | ''           | ''        | 'IO'  | ''      | ''           | ''   | ''     | ''            | ''  | ''         | ''      | '20141104' | ''    
 'LASER_MARK_LABELS_10X60T' | 'Mech'    | 'EMPTY'  | 'DUMMY16'(!)   = ''       | ''        | 'DUMMY16'   |'LASER_MARK_LABELS_10X60T'| 'LASER_MARK_LABELS_10X60_FOR TOP' | ''      | ''       | ''           | ''        | 'IO'  | ''      | 'S2V-JOSEPH' | ''   | ''     | ''            | ''  | ''         | ''      | '20150622' | ''    
 'LASER_MARK_LABELS_10X10B' | 'Mech'    | 'EMPTY'  | 'DUMMY17'(!)   = ''       | ''        | 'DUMMY17'   |'LASER_MARK_LABELS_10X10B'| 'LASER_MARK_LABELS_10X10_FOR BOT' | ''      | ''       | ''           | ''        | 'IO'  | ''      | 'S2V-JOSEPH' | ''   | ''     | ''            | ''  | ''         | ''      | '20150622' | ''    
 'LASER_MARK_LABELS_12X12T' | 'Mech'    | 'EMPTY'  | 'DUMMY33'(!)   = ''       | ''        | 'DUMMY33'   |'LASER_MARK_LABELS_12X12T'| 'LASER_MARK_LABELS_12X12_FOR TOP' | ''      | ''       | ''           | ''        | 'IO'  | ''      | ''           | ''   | ''     | ''            | ''  | ''         | ''      | '20161110' | ''    
 'LASER_MARK_LABELS_4X12T'  | 'Mech'    | 'EMPTY'  | 'DUMMY39'(!)   = ''       | ''        | 'DUMMY39'   |'LASER_MARK_LABELS_4X12T'| 'LASER_MARK_LABELS_4X12T'         | ''      | ''       | ''           | ''        | 'IO'  | ''      | ''           | ''   | ''     | ''            | ''  | ''         | ''      | '20170125' | ''    
 'LASER_MARK_LABELS_3X3T'   | 'Mech'    | 'EMPTY'  | 'DUMMY64'(!)   = ''       | ''        | 'DUMMY64'   |'LASER_MARK_LABELS_3X3T'| 'LASER_MARK_LABELS_3X3T'          | ''      | ''       | ''           | ''        | 'IO'  | ''      | ''           | ''   | ''     | ''            | ''  | ''         | ''      | '20190724' | ''    

END_PART

END.

